# BASEBOARD_FAB2 (Tioga Pass) — schematic netlist excerpt (pin names and nets, part order shuffled) for the footprints in the layout excerpt that follows; sources: Cadence DE-HDL packaged netlist, KiCad conversion of Wiwynn_Tioga_Pass_MB.brd

C4A1  CAP  22UF 4V 20% X6S  pkg 0805LF  page 222 : A = PVTT_DEF ; B = GND
R2U34  RES  20.0 1% CHIP  pkg 0402  page 159 : A = SMB_HOST_STBY_LVC3_SCL_R ; B = SMB_HOST_STBY_LVC3_SCL
R1E11  RES  10.0K 1% EMPTY  pkg 0402  page 161 : A = P3V3_STBY ; B = FM_ENABLE_FAN_POWER

(kicad_pcb
	(version 20260206)
	(generator "pcbnew")
	(generator_version "10.0")
	(general
		(thickness 1.6)
		(legacy_teardrops no)
	)
	(paper "A4")
	(title_block
		(title "Wiwynn_Tioga_Pass_MB.brd")
		(comment 1 "Tioga Pass / footprints 203-205 of 4770")
	)
	(layers
		(0 "F.Cu" signal "TOP")
		(4 "In1.Cu" signal "L2GND")
		(6 "In2.Cu" signal "L3")
		(8 "In3.Cu" signal "L4GND")
		(10 "In4.Cu" signal "L5")
		(12 "In5.Cu" signal "L6GND")
		(14 "In6.Cu" signal "L7VCC")
		(16 "In7.Cu" signal "L8VCC")
		(18 "In8.Cu" signal "L9GND")
		(20 "In9.Cu" signal "L10")
		(22 "In10.Cu" signal "L11GND")
		(24 "In11.Cu" signal "L12")
		(26 "In12.Cu" signal "L13GND")
		(2 "B.Cu" signal "BOTTOM")
		(9 "F.Adhes" user "F.Adhesive")
		(11 "B.Adhes" user "B.Adhesive")
		(13 "F.Paste" user "Package Geometry/Pastemask Top")
		(15 "B.Paste" user "Package Geometry/Pastemask Bottom")
		(5 "F.SilkS" user "Ref Des/Silkscreen Top")
		(7 "B.SilkS" user "Ref Des/Silkscreen Bottom")
		(1 "F.Mask" user "Board Geometry/Soldermask Top")
		(3 "B.Mask" user "Board Geometry/Soldermask Bottom")
		(17 "Dwgs.User" user "User.Drawings")
		(19 "Cmts.User" user "User.Comments")
		(21 "Eco1.User" user "User.Eco1")
		(23 "Eco2.User" user "User.Eco2")
		(25 "Edge.Cuts" user "Board Geometry/Outline")
		(27 "Margin" user)
		(31 "F.CrtYd" user "Package Geometry/Place Bound Top")
		(29 "B.CrtYd" user "Package Geometry/Place Bound Bottom")
		(35 "F.Fab" user "Ref Des/Assembly Top")
		(33 "B.Fab" user "Ref Des/Assembly Bottom")
	)
	(footprint ""
		(layer "F.Cu")
		(at 17.5768 -43.6626 90)
		(property "Reference" "R1E11"
			(at 0 0 90)
			(layer "F.SilkS")
			(hide yes)
			(effects
				(font
					(size 1.27 1.27)
				)
			)
		)
		(property "Value" ""
			(at 0 0 90)
			(layer "F.Fab")
			(effects
				(font
					(size 1.27 1.27)
				)
			)
		)
		(duplicate_pad_numbers_are_jumpers no)
		(fp_rect
			(start 0.2794 -0.1016)
			(end -0.2794 0.9906)
			(stroke
				(width 0)
				(type default)
			)
			(fill no)
			(layer "F.CrtYd")
		)
		(fp_line
			(start 0.2794 -0.1016)
			(end -0.2794 -0.1016)
			(stroke
				(width 0.1)
				(type default)
			)
			(layer "F.Fab")
		)
		(fp_line
			(start -0.2794 -0.1016)
			(end -0.2794 0.9906)
			(stroke
				(width 0.1)
				(type default)
			)
			(layer "F.Fab")
		)
		(fp_line
			(start 0.2794 0.9906)
			(end 0.2794 -0.1016)
			(stroke
				(width 0.1)
				(type default)
			)
			(layer "F.Fab")
		)
		(fp_line
			(start -0.2794 0.9906)
			(end 0.2794 0.9906)
			(stroke
				(width 0.1)
				(type default)
			)
			(layer "F.Fab")
		)
		(pad "1" smd rect
			(at 0 0 90)
			(size 0.508 0.508)
			(layers "F.Cu" "F.Mask" "F.Paste")
			(net "P3V3_STBY")
		)
		(pad "2" smd rect
			(at 0 0.889 90)
			(size 0.508 0.508)
			(layers "F.Cu" "F.Mask" "F.Paste")
			(net "FM_ENABLE_FAN_POWER")
		)
		(zone
			(layer "F.Cu")
			(hatch none 0.5)
			(connect_pads
				(clearance 0)
			)
			(min_thickness 0.25)
			(keepout
				(tracks allowed)
				(vias not_allowed)
				(pads allowed)
				(copperpour not_allowed)
				(footprints allowed)
			)
			(placement
				(enabled no)
				(sheetname "")
			)
			(fill
				(thermal_gap 0.5)
				(thermal_bridge_width 0.5)
				(island_removal_mode 0)
			)
			(polygon
				(pts
					(xy 17.8308 -43.9166) (xy 17.8308 -43.4086) (xy 18.2118 -43.4086) (xy 18.2118 -43.9166)
				)
			)
		)
		(zone
			(layer "F.Cu")
			(hatch none 0.5)
			(connect_pads
				(clearance 0)
			)
			(min_thickness 0.25)
			(keepout
				(tracks not_allowed)
				(vias allowed)
				(pads allowed)
				(copperpour not_allowed)
				(footprints allowed)
			)
			(placement
				(enabled no)
				(sheetname "")
			)
			(fill
				(thermal_gap 0.5)
				(thermal_bridge_width 0.5)
				(island_removal_mode 0)
			)
			(polygon
				(pts
					(xy 17.8308 -43.9166) (xy 17.8308 -43.4086) (xy 18.2118 -43.4086) (xy 18.2118 -43.9166)
				)
			)
		)
	)
	(footprint ""
		(layer "F.Cu")
		(at 181.763924 -153.6827 90)
		(property "Reference" "C4A1"
			(at 0 0 90)
			(layer "F.SilkS")
			(hide yes)
			(effects
				(font
					(size 1.27 1.27)
				)
			)
		)
		(property "Value" ""
			(at 0 0 90)
			(layer "F.Fab")
			(effects
				(font
					(size 1.27 1.27)
				)
			)
		)
		(duplicate_pad_numbers_are_jumpers no)
		(fp_rect
			(start 0.7239 1.9939)
			(end -0.7239 -0.2159)
			(stroke
				(width 0)
				(type default)
			)
			(fill no)
			(layer "F.CrtYd")
		)
		(fp_line
			(start 0.7239 -0.2159)
			(end -0.7239 -0.2159)
			(stroke
				(width 0.1)
				(type default)
			)
			(layer "F.Fab")
		)
		(fp_line
			(start -0.7239 -0.2159)
			(end -0.7239 1.9939)
			(stroke
				(width 0.1)
				(type default)
			)
			(layer "F.Fab")
		)
		(fp_line
			(start 0.7239 1.9939)
			(end 0.7239 -0.2159)
			(stroke
				(width 0.1)
				(type default)
			)
			(layer "F.Fab")
		)
		(fp_line
			(start -0.7239 1.9939)
			(end 0.7239 1.9939)
			(stroke
				(width 0.1)
				(type default)
			)
			(layer "F.Fab")
		)
		(pad "1" smd rect
			(at 0 0 90)
			(size 1.27 1.016)
			(layers "F.Cu" "F.Mask" "F.Paste")
			(net "PVTT_DEF")
		)
		(pad "2" smd rect
			(at 0 1.778 90)
			(size 1.27 1.016)
			(layers "F.Cu" "F.Mask" "F.Paste")
			(net "GND")
		)
		(zone
			(layer "F.Cu")
			(hatch none 0.5)
			(connect_pads
				(clearance 0)
			)
			(min_thickness 0.25)
			(keepout
				(tracks not_allowed)
				(vias allowed)
				(pads allowed)
				(copperpour not_allowed)
				(footprints allowed)
			)
			(placement
				(enabled no)
				(sheetname "")
			)
			(fill
				(thermal_gap 0.5)
				(thermal_bridge_width 0.5)
				(island_removal_mode 0)
			)
			(polygon
				(pts
					(xy 183.033924 -154.3177) (xy 182.271924 -154.3177) (xy 182.271924 -153.0477) (xy 183.033924 -153.0477)
				)
			)
		)
	)
	(footprint ""
		(layer "F.Cu")
		(at 402.66874 -33.664652 -90)
		(property "Reference" "R2U34"
			(at 0 0 270)
			(layer "F.SilkS")
			(hide yes)
			(effects
				(font
					(size 1.27 1.27)
				)
			)
		)
		(property "Value" ""
			(at 0 0 270)
			(layer "F.Fab")
			(effects
				(font
					(size 1.27 1.27)
				)
			)
		)
		(duplicate_pad_numbers_are_jumpers no)
		(fp_poly
			(pts
				(xy -0.2794 -0.1016) (xy 0.2794 -0.1016) (xy 0.2794 0.9906) (xy -0.2794 0.9906)
			)
			(stroke
				(width 0)
				(type default)
			)
			(fill no)
			(layer "F.CrtYd")
		)
		(fp_line
			(start -0.2794 0.9906)
			(end 0.2794 0.9906)
			(stroke
				(width 0.1)
				(type default)
			)
			(layer "F.Fab")
		)
		(fp_line
			(start 0.2794 0.9906)
			(end 0.2794 -0.1016)
			(stroke
				(width 0.1)
				(type default)
			)
			(layer "F.Fab")
		)
		(fp_line
			(start -0.2794 -0.1016)
			(end -0.2794 0.9906)
			(stroke
				(width 0.1)
				(type default)
			)
			(layer "F.Fab")
		)
		(fp_line
			(start 0.2794 -0.1016)
			(end -0.2794 -0.1016)
			(stroke
				(width 0.1)
				(type default)
			)
			(layer "F.Fab")
		)
		(pad "1" smd rect
			(at 0 0 270)
			(size 0.508 0.508)
			(layers "F.Cu" "F.Mask" "F.Paste")
			(net "SMB_HOST_STBY_LVC3_SCL_R")
		)
		(pad "2" smd rect
			(at 0 0.889 270)
			(size 0.508 0.508)
			(layers "F.Cu" "F.Mask" "F.Paste")
			(net "SMB_HOST_STBY_LVC3_SCL")
		)
		(zone
			(layer "F.Cu")
			(hatch none 0.5)
			(connect_pads
				(clearance 0)
			)
			(min_thickness 0.25)
			(keepout
				(tracks not_allowed)
				(vias allowed)
				(pads allowed)
				(copperpour not_allowed)
				(footprints allowed)
			)
			(placement
				(enabled no)
				(sheetname "")
			)
			(fill
				(thermal_gap 0.5)
				(thermal_bridge_width 0.5)
				(island_removal_mode 0)
			)
			(polygon
				(pts
					(xy 402.03374 -33.918652) (xy 402.03374 -33.410652) (xy 402.41474 -33.410652) (xy 402.41474 -33.918652)
				)
			)
		)
		(zone
			(layer "F.Cu")
			(hatch none 0.5)
			(connect_pads
				(clearance 0)
			)
			(min_thickness 0.25)
			(keepout
				(tracks allowed)
				(vias not_allowed)
				(pads allowed)
				(copperpour not_allowed)
				(footprints allowed)
			)
			(placement
				(enabled no)
				(sheetname "")
			)
			(fill
				(thermal_gap 0.5)
				(thermal_bridge_width 0.5)
				(island_removal_mode 0)
			)
			(polygon
				(pts
					(xy 402.41474 -33.918652) (xy 402.41474 -33.410652) (xy 402.03374 -33.410652) (xy 402.03374 -33.918652)
				)
			)
		)
	)
)
